FILE_TYPE = CONNECTIVITY;
{Allegro Design Entry HDL 17.2-2016 S081 (4005846) 1/11/2022}
"PAGE_NUMBER" = 173;
0"NC";
1"DMI_CPU0_PCH_TX_C_DP<7:0>";
2"DMI_CPU0_PCH_TX_C_DN<7:0>";
3"DMI_CPU0_PCH_RX_DN<7:0>";
4"DMI_CPU0_PCH_RX_DP<7:0>";
5"DMI_CPU0_PCH_RX_DP<3>";
6"DMI_CPU0_PCH_RX_DN<2>";
7"P3E_PCH_NVS_TX_C_DP<1>";
8"P3E_PCH_NVS_TX_C_DP<0>";
9"USB3_PCH_TX_C_DP<4>";
10"USB3_PCH_TX_C_DN<4>";
11"P3E_PCH_NVS_TX_C_DN<0>";
12"P3E_PCH_BMC_TX_C_DP";
13"P3E_PCH_BMC_TX_C_DN";
14"P3E_PCH_NVS_TX_C_DN<1>";
15"P3E_PCH_E1S_TX_C_DN<3>";
16"P3E_PCH_E1S_TX_C_DP<3>";
17"P3E_PCH_E1S_TX_C_DP<2>";
18"P3E_PCH_E1S_TX_C_DN<1>";
19"P3E_PCH_E1S_TX_C_DP<0>";
20"P3E_PCH_M2_TX_C_DN<2>";
21"P3E_PCH_M2_TX_C_DP<1>";
22"P3E_PCH_M2_TX_C_DN<3>";
23"P3E_PCH_M2_TX_C_DP<3>";
24"P3E_PCH_E1S_TX_C_DP<1>";
25"P3E_PCH_E1S_TX_C_DN<2>";
26"P3E_PCH_E1S_TX_C_DN<0>";
27"P3E_PCH_M2_TX_C_DN<0>";
28"P3E_PCH_M2_TX_C_DN<1>";
29"P3E_PCH_M2_TX_C_DP<2>";
30"P3E_PCH_M2_TX_C_DP<0>";
31"P3E_PCH_BMC_TX_DP";
32"P3E_PCH_BMC_TX_DN";
33"P3E_PCH_E1S_TX_DP<3>";
34"P3E_PCH_E1S_TX_DP<2>";
35"P3E_PCH_E1S_TX_DN<3>";
36"P3E_PCH_M2_TX_DN<1>";
37"P3E_PCH_M2_TX_DP<1>";
38"P3E_PCH_M2_TX_DN<2>";
39"P3E_PCH_M2_TX_DP<2>";
40"P3E_PCH_M2_TX_DP<3>";
41"P3E_PCH_E1S_TX_DN<2>";
42"P3E_PCH_E1S_TX_DP<0>";
43"P3E_PCH_E1S_TX_DN<0>";
44"P3E_PCH_M2_TX_DN<3>";
45"P3E_PCH_M2_TX_DP<0>";
46"P3E_PCH_E1S_TX_DP<1>";
47"P3E_PCH_E1S_TX_DN<1>";
48"P3E_PCH_M2_TX_DN<0>";
49"NC_PCH_RSVD<10>";
50"NC_PCH_RSVD<11>";
51"TP_P3E_PCH_12_TX_DP";
52"TP_P3E_PCH_12_TX_DN";
53"TP_P3E_PCH_13_TX_DN";
54"TP_P3E_PCH_13_TX_DP";
55"P3E_PCH_NVS_TX_DP<1>";
56"P3E_PCH_NVS_TX_DP<0>";
57"P3E_PCH_NVS_TX_DN<0>";
58"USB3_PCH_TX_DN<4>";
59"USB3_PCH_TX_DP<4>";
60"P3E_PCH_NVS_TX_DN<1>";
61"TP_P3E_PCH_15_TX_DP";
62"TP_P3E_PCH_14_TX_DP";
63"TP_P3E_PCH_14_TX_DN";
64"TP_P3E_PCH_15_TX_DN";
65"DMI_CPU0_PCH_RX_DN<0>";
66"DMI_CPU0_PCH_RX_DP<0>";
67"DMI_CPU0_PCH_RX_DN<1>";
68"DMI_CPU0_PCH_RX_DP<1>";
69"DMI_CPU0_PCH_RX_DP<2>";
70"DMI_CPU0_PCH_RX_DN<3>";
71"DMI_CPU0_PCH_RX_DN<4>";
72"DMI_CPU0_PCH_RX_DP<4>";
73"DMI_CPU0_PCH_RX_DN<5>";
74"DMI_CPU0_PCH_RX_DP<5>";
75"DMI_CPU0_PCH_RX_DP<6>";
76"DMI_CPU0_PCH_TX_C_DN<0>";
77"DMI_CPU0_PCH_TX_C_DN<5>";
78"DMI_CPU0_PCH_TX_C_DN<2>";
79"DMI_CPU0_PCH_TX_C_DN<1>";
80"DMI_CPU0_PCH_TX_C_DN<3>";
81"DMI_CPU0_PCH_TX_C_DN<4>";
82"DMI_CPU0_PCH_RX_DN<7>";
83"DMI_CPU0_PCH_RX_DP<7>";
84"DMI_CPU0_PCH_RX_DN<6>";
85"DMI_CPU0_PCH_TX_C_DN<7>";
86"DMI_CPU0_PCH_TX_C_DN<6>";
87"P3E_PCH_BMC_RX_DP";
88"P3E_PCH_BMC_RX_DN";
89"P3E_PCH_E1S_RX_DN<3>";
90"P3E_PCH_E1S_RX_DP<3>";
91"NC_PCH_RSVD<8>";
92"P3E_PCH_M2_RX_DN<1>";
93"P3E_PCH_M2_RX_DP<1>";
94"P3E_PCH_M2_RX_DN<2>";
95"P3E_PCH_M2_RX_DN<0>";
96"P3E_PCH_M2_RX_DN<3>";
97"P3E_PCH_M2_RX_DP<2>";
98"P3E_PCH_M2_RX_DP<3>";
99"P3E_PCH_E1S_RX_DN<0>";
100"P3E_PCH_E1S_RX_DP<2>";
101"P3E_PCH_E1S_RX_DP<0>";
102"P3E_PCH_E1S_RX_DN<1>";
103"P3E_PCH_E1S_RX_DP<1>";
104"P3E_PCH_M2_RX_DP<0>";
105"P3E_PCH_E1S_RX_DN<2>";
106"NC_PCH_RSVD<9>";
107"TP_P3E_PCH_13_RX_DN";
108"TP_P3E_PCH_12_RX_DN";
109"TP_P3E_PCH_12_RX_DP";
110"TP_P3E_PCH_13_RX_DP";
111"TP_P3E_PCH_15_RX_DN";
112"TP_P3E_PCH_14_RX_DP";
113"TP_P3E_PCH_14_RX_DN";
114"P3E_PCH_NVS_RX_DP<1>";
115"P3E_PCH_NVS_RX_DN<1>";
116"USB3_PCH_RX_BUF_DN<4>";
117"USB3_PCH_RX_BUF_DP<4>";
118"P3E_PCH_NVS_RX_DN<0>";
119"P3E_PCH_NVS_RX_DP<0>";
120"TP_P3E_PCH_15_RX_DP";
121"DMI_CPU0_PCH_TX_C_DP<7>";
122"DMI_CPU0_PCH_TX_C_DP<6>";
123"DMI_CPU0_PCH_TX_C_DP<5>";
124"DMI_CPU0_PCH_TX_C_DP<0>";
125"DMI_CPU0_PCH_TX_C_DP<1>";
126"DMI_CPU0_PCH_TX_C_DP<2>";
127"DMI_CPU0_PCH_TX_C_DP<3>";
128"DMI_CPU0_PCH_TX_C_DP<4>";
129"PCH_PCIEUP_RCOMPP";
130"PCH_PCIEUP_RCOMPN";
%"Q_RES"
"2","(-2975,550)","0","pure_quanta","I1";
;
PART_NUMBER"CS11002FB07"
MATERIAL"CHIP"
TOLERANCE"1%"
VALUE"100"
WATTAGE"1/16W"
PACK_TYPE"0402LF"
$LOCATION"R495"
CDS_LIB"pure_quanta"
CDS_LOCATION"R495"
$SEC"1"
CDS_SEC"1";
"A"
$PN"1"129;
"B"
$PN"2"130;
%"EMMITSBURG_REV0P9"
"3","(425,2000)","0","pure_quanta","I110";
;
PART_NUMBER"AJ0QV2N0T00"
PART_TYPE"SMLF"
VALUE"GFNOCPU04302300-QV2N-MM#99A1WT"
MATERIAL"IC"
$LOCATION"U4"
NEEDS_NO_SIZE"TRUE"
CDS_LMAN_SYM_OUTLINE"-1350,1475,1350,-1475"
CDS_LIB"pure_quanta"
CDS_LOCATION"U4"
$SEC"3"
CDS_SEC"3";
"SATA_9_PCIE3_9_USB3_9_TXP"
$PN"AG32"59;
"SATA_9_PCIE3_9_USB3_9_TXN"
$PN"AE32"58;
"SATA_9_PCIE3_9_USB3_9_RXP"
$PN"R42"117;
"SATA_9_PCIE3_9_USB3_9_RXN"
$PN"R40"116;
"SATA_8_PCIE3_8_USB3_8_TXP"
$PN"AD37"31;
"SATA_8_PCIE3_8_USB3_8_TXN"
$PN"AE36"32;
"SATA_8_PCIE3_8_USB3_8_RXP"
$PN"U43"87;
"SATA_8_PCIE3_8_USB3_8_RXN"
$PN"U41"88;
"SATA_7_PCIE3_7_USB3_7_TXP"
$PN"AG36"33;
"SATA_7_PCIE3_7_USB3_7_TXN"
$PN"AF34"35;
"SATA_7_PCIE3_7_USB3_7_RXP"
$PN"V42"90;
"SATA_7_PCIE3_7_USB3_7_RXN"
$PN"V40"89;
"SATA_6_PCIE3_6_USB3_6_TXP"
$PN"AH37"34;
"SATA_6_PCIE3_6_USB3_6_TXN"
$PN"AF37"41;
"SATA_6_PCIE3_6_USB3_6_RXP"
$PN"W43"100;
"SATA_6_PCIE3_6_USB3_6_RXN"
$PN"W41"105;
"SATA_5_PCIE3_5_USB3_5_TXP"
$PN"AJ32"46;
"SATA_5_PCIE3_5_USB3_5_TXN"
$PN"AH34"47;
"SATA_5_PCIE3_5_USB3_5_RXP"
$PN"Y42"103;
"SATA_5_PCIE3_5_USB3_5_RXN"
$PN"Y40"102;
"SATA_4_PCIE3_4_USB3_4_TXP"
$PN"AM37"42;
"SATA_4_PCIE3_4_USB3_4_TXN"
$PN"AL36"43;
"SATA_4_PCIE3_4_USB3_4_RXP"
$PN"AA43"101;
"SATA_4_PCIE3_4_USB3_4_RXN"
$PN"AA41"99;
"SATA_3_PCIE3_3_USB3_3_TXP"
$PN"AM34"40;
"SATA_3_PCIE3_3_USB3_3_TXN"
$PN"AK34"44;
"SATA_3_PCIE3_3_USB3_3_RXP"
$PN"AB42"98;
"SATA_3_PCIE3_3_USB3_3_RXN"
$PN"AB40"96;
"SATA_2_PCIE3_2_USB3_2_TXP"
$PN"AT37"39;
"SATA_2_PCIE3_2_USB3_2_TXN"
$PN"AR36"38;
"SATA_2_PCIE3_2_USB3_2_RXP"
$PN"AC43"97;
"SATA_2_PCIE3_2_USB3_2_RXN"
$PN"AC41"94;
"SATA_1_PCIE3_1_USB3_1_TXP"
$PN"AP34"37;
"SATA_1_PCIE3_1_USB3_1_TXN"
$PN"AN36"36;
"SATA_1_PCIE3_1_USB3_1_RXP"
$PN"AD42"93;
"SATA_1_PCIE3_1_USB3_1_RXN"
$PN"AD40"92;
"SATA_15_PCIE3_15_TXP"
$PN"N36"61;
"SATA_15_PCIE3_15_TXN"
$PN"P34"64;
"SATA_15_PCIE3_15_RXP"
$PN"G42"120;
"SATA_15_PCIE3_15_RXN"
$PN"G40"111;
"SATA_14_PCIE3_14_GBE_2_TXP"
$PN"T34"62;
"SATA_14_PCIE3_14_GBE_2_TXN"
$PN"R32"63;
"SATA_14_PCIE3_14_GBE_2_RXP"
$PN"H43"112;
"SATA_14_PCIE3_14_GBE_2_RXN"
$PN"H41"113;
"SATA_13_PCIE3_13_TXP"
$PN"W32"54;
"SATA_13_PCIE3_13_TXN"
$PN"U32"53;
"SATA_13_PCIE3_13_RXP"
$PN"J42"110;
"SATA_13_PCIE3_13_RXN"
$PN"J40"107;
"SATA_12_PCIE3_12_GBE_1_TXP"
$PN"U36"51;
"SATA_12_PCIE3_12_GBE_1_TXN"
$PN"V34"52;
"SATA_12_PCIE3_12_GBE_1_RXP"
$PN"K43"109;
"SATA_12_PCIE3_12_GBE_1_RXN"
$PN"K41"108;
"SATA_11_PCIE3_11_TXP"
$PN"V37"55;
"SATA_11_PCIE3_11_TXN"
$PN"T37"60;
"SATA_11_PCIE3_11_RXP"
$PN"L42"114;
"SATA_11_PCIE3_11_RXN"
$PN"L40"115;
"SATA_10_PCIE3_10_GBE_0_TXP"
$PN"Y37"56;
"SATA_10_PCIE3_10_GBE_0_TXN"
$PN"W36"57;
"SATA_10_PCIE3_10_GBE_0_RXP"
$PN"M43"119;
"SATA_10_PCIE3_10_GBE_0_RXN"
$PN"M41"118;
"SATA_0_PCIE3_0_USB3_0_TXP"
$PN"AK31"45;
"SATA_0_PCIE3_0_USB3_0_TXN"
$PN"AL32"48;
"SATA_0_PCIE3_0_USB3_0_RXP"
$PN"AE43"104;
"SATA_0_PCIE3_0_USB3_0_RXN"
$PN"AE41"95;
"RSVD_C40"
$PN"C40"91;
"RSVD_D39"
$PN"D39"106;
"RSVD_N40"
$PN"N40"49;
"RSVD_N42"
$PN"N42"50;
"PHY_PCIE3_RCOMPP"
$PN"AR29"129;
"PHY_PCIE3_RCOMPN"
$PN"AP31"130;
"DMI_7_SATA_16_PCIE3_16_TXP"
$PN"H37"83;
"DMI_7_SATA_16_PCIE3_16_TXN"
$PN"F37"82;
"DMI_7_SATA_16_PCIE3_16_RXP"
$PN"D37"121;
"DMI_7_SATA_16_PCIE3_16_RXN"
$PN"B37"85;
"DMI_6_SATA_17_PCIE3_17_TXP"
$PN"J36"75;
"DMI_6_SATA_17_PCIE3_17_TXN"
$PN"K37"84;
"DMI_6_SATA_17_PCIE3_17_RXP"
$PN"C36"122;
"DMI_6_SATA_17_PCIE3_17_RXN"
$PN"A36"86;
"DMI_5_SATA_18_PCIE3_18_TXP"
$PN"H34"74;
"DMI_5_SATA_18_PCIE3_18_TXN"
$PN"G36"73;
"DMI_5_SATA_18_PCIE3_18_RXP"
$PN"D35"123;
"DMI_5_SATA_18_PCIE3_18_RXN"
$PN"B35"77;
"DMI_4_SATA_19_PCIE3_19_TXP"
$PN"G32"72;
"DMI_4_SATA_19_PCIE3_19_TXN"
$PN"J32"71;
"DMI_4_SATA_19_PCIE3_19_RXP"
$PN"C34"128;
"DMI_4_SATA_19_PCIE3_19_RXN"
$PN"A34"81;
"DMI_3_TXP"
$PN"K31"5;
"DMI_3_TXN"
$PN"L32"70;
"DMI_3_RXP"
$PN"D33"127;
"DMI_3_RXN"
$PN"B33"80;
"DMI_2_TXP"
$PN"H31"69;
"DMI_2_TXN"
$PN"J29"6;
"DMI_2_RXP"
$PN"C32"126;
"DMI_2_RXN"
$PN"A32"78;
"DMI_1_TXP"
$PN"F28"68;
"DMI_1_TXN"
$PN"G29"67;
"DMI_1_RXP"
$PN"D31"125;
"DMI_1_RXN"
$PN"B31"79;
"DMI_0_TXP"
$PN"H28"66;
"DMI_0_TXN"
$PN"K28"65;
"DMI_0_RXP"
$PN"C30"124;
"DMI_0_RXN"
$PN"A30"76;
%"TAP"
"1","(-1625,2625)","2","standard","I26";
;
HDL_TAP"TRUE"
BODY_TYPE"PLUMBING"
CDS_LIB"standard";
"B \NAC \NWC"1;
"S \NAC"
BN"7"121;
%"TAP"
"1","(-1475,2575)","2","standard","I27";
;
HDL_TAP"TRUE"
BODY_TYPE"PLUMBING"
CDS_LIB"standard";
"B \NAC \NWC"2;
"S \NAC"
BN"7"85;
%"TAP"
"1","(-1475,2675)","2","standard","I28";
;
HDL_TAP"TRUE"
BODY_TYPE"PLUMBING"
CDS_LIB"standard";
"B \NAC \NWC"2;
"S \NAC"
BN"6"86;
%"TAP"
"1","(-1625,2725)","2","standard","I31";
;
HDL_TAP"TRUE"
BODY_TYPE"PLUMBING"
CDS_LIB"standard";
"B \NAC \NWC"1;
"S \NAC"
BN"6"122;
%"TAP"
"1","(-1625,2825)","2","standard","I32";
;
HDL_TAP"TRUE"
BODY_TYPE"PLUMBING"
CDS_LIB"standard";
"B \NAC \NWC"1;
"S \NAC"
BN"5"123;
%"TAP"
"1","(-1625,2925)","2","standard","I33";
;
HDL_TAP"TRUE"
BODY_TYPE"PLUMBING"
CDS_LIB"standard";
"B \NAC \NWC"1;
"S \NAC"
BN"4"128;
%"TAP"
"1","(-1475,2775)","2","standard","I34";
;
HDL_TAP"TRUE"
BODY_TYPE"PLUMBING"
CDS_LIB"standard";
"B \NAC \NWC"2;
"S \NAC"
BN"5"77;
%"TAP"
"1","(-1475,2875)","2","standard","I35";
;
HDL_TAP"TRUE"
BODY_TYPE"PLUMBING"
CDS_LIB"standard";
"B \NAC \NWC"2;
"S \NAC"
BN"4"81;
%"TAP"
"1","(-1625,3025)","2","standard","I36";
;
HDL_TAP"TRUE"
BODY_TYPE"PLUMBING"
CDS_LIB"standard";
"B \NAC \NWC"1;
"S \NAC"
BN"3"127;
%"TAP"
"1","(-1625,3225)","2","standard","I37";
;
HDL_TAP"TRUE"
BODY_TYPE"PLUMBING"
CDS_LIB"standard";
"B \NAC \NWC"1;
"S \NAC"
BN"1"125;
%"TAP"
"1","(-1625,3125)","2","standard","I38";
;
HDL_TAP"TRUE"
BODY_TYPE"PLUMBING"
CDS_LIB"standard";
"B \NAC \NWC"1;
"S \NAC"
BN"2"126;
%"TAP"
"1","(-1475,3075)","2","standard","I39";
;
HDL_TAP"TRUE"
BODY_TYPE"PLUMBING"
CDS_LIB"standard";
"B \NAC \NWC"2;
"S \NAC"
BN"2"78;
%"TAP"
"1","(-1475,2975)","2","standard","I40";
;
HDL_TAP"TRUE"
BODY_TYPE"PLUMBING"
CDS_LIB"standard";
"B \NAC \NWC"2;
"S \NAC"
BN"3"80;
%"TAP"
"1","(-1475,3175)","2","standard","I41";
;
HDL_TAP"TRUE"
BODY_TYPE"PLUMBING"
CDS_LIB"standard";
"B \NAC \NWC"2;
"S \NAC"
BN"1"79;
%"TAP"
"1","(-1625,3325)","2","standard","I42";
;
HDL_TAP"TRUE"
BODY_TYPE"PLUMBING"
CDS_LIB"standard";
"B \NAC \NWC"1;
"S \NAC"
BN"0"124;
%"TAP"
"1","(-1475,3275)","2","standard","I43";
;
HDL_TAP"TRUE"
BODY_TYPE"PLUMBING"
CDS_LIB"standard";
"B \NAC \NWC"2;
"S \NAC"
BN"0"76;
%"TAP"
"1","(2325,2575)","0","standard","I44";
;
HDL_TAP"TRUE"
BODY_TYPE"PLUMBING"
CDS_LIB"standard";
"B \NAC \NWC"3;
"S \NAC"
BN"7"82;
%"TAP"
"1","(2325,2675)","0","standard","I45";
;
HDL_TAP"TRUE"
BODY_TYPE"PLUMBING"
CDS_LIB"standard";
"B \NAC \NWC"3;
"S \NAC"
BN"6"84;
%"TAP"
"1","(2475,2625)","0","standard","I46";
;
HDL_TAP"TRUE"
BODY_TYPE"PLUMBING"
CDS_LIB"standard";
"B \NAC \NWC"4;
"S \NAC"
BN"7"83;
%"TAP"
"1","(2325,2775)","0","standard","I47";
;
HDL_TAP"TRUE"
BODY_TYPE"PLUMBING"
CDS_LIB"standard";
"B \NAC \NWC"3;
"S \NAC"
BN"5"73;
%"TAP"
"1","(2325,2875)","0","standard","I48";
;
HDL_TAP"TRUE"
BODY_TYPE"PLUMBING"
CDS_LIB"standard";
"B \NAC \NWC"3;
"S \NAC"
BN"4"71;
%"TAP"
"1","(2325,2975)","0","standard","I49";
;
HDL_TAP"TRUE"
BODY_TYPE"PLUMBING"
CDS_LIB"standard";
"B \NAC \NWC"3;
"S \NAC"
BN"3"70;
%"TAP"
"1","(2325,3075)","0","standard","I50";
;
HDL_TAP"TRUE"
BODY_TYPE"PLUMBING"
CDS_LIB"standard";
"B \NAC \NWC"3;
"S \NAC"
BN"2"6;
%"TAP"
"1","(2325,3175)","0","standard","I51";
;
HDL_TAP"TRUE"
BODY_TYPE"PLUMBING"
CDS_LIB"standard";
"B \NAC \NWC"3;
"S \NAC"
BN"1"67;
%"TAP"
"1","(2475,2725)","0","standard","I52";
;
HDL_TAP"TRUE"
BODY_TYPE"PLUMBING"
CDS_LIB"standard";
"B \NAC \NWC"4;
"S \NAC"
BN"6"75;
%"TAP"
"1","(2475,2825)","0","standard","I53";
;
HDL_TAP"TRUE"
BODY_TYPE"PLUMBING"
CDS_LIB"standard";
"B \NAC \NWC"4;
"S \NAC"
BN"5"74;
%"TAP"
"1","(2475,2925)","0","standard","I54";
;
HDL_TAP"TRUE"
BODY_TYPE"PLUMBING"
CDS_LIB"standard";
"B \NAC \NWC"4;
"S \NAC"
BN"4"72;
%"TAP"
"1","(2475,3025)","0","standard","I55";
;
HDL_TAP"TRUE"
BODY_TYPE"PLUMBING"
CDS_LIB"standard";
"B \NAC \NWC"4;
"S \NAC"
BN"3"5;
%"TAP"
"1","(2475,3125)","0","standard","I56";
;
HDL_TAP"TRUE"
BODY_TYPE"PLUMBING"
CDS_LIB"standard";
"B \NAC \NWC"4;
"S \NAC"
BN"2"69;
%"TAP"
"1","(2475,3225)","0","standard","I57";
;
HDL_TAP"TRUE"
BODY_TYPE"PLUMBING"
CDS_LIB"standard";
"B \NAC \NWC"4;
"S \NAC"
BN"1"68;
%"TAP"
"1","(2325,3275)","0","standard","I58";
;
HDL_TAP"TRUE"
BODY_TYPE"PLUMBING"
CDS_LIB"standard";
"B \NAC \NWC"3;
"S \NAC"
BN"0"65;
%"TAP"
"1","(2475,3325)","0","standard","I59";
;
HDL_TAP"TRUE"
BODY_TYPE"PLUMBING"
CDS_LIB"standard";
"B \NAC \NWC"4;
"S \NAC"
BN"0"66;
%"Q_CAP_DIFFBUS"
"2","(3025,925)","0","pure_quanta","I60";
;
PART_NUMBER"SP_CH4221MEE01"
VALUE"DIFF BUS_0.22UF"
VOLTAGE"6.3V"
TOLERANCE"20%"
PACK_TYPE"C0201"
MATERIAL"X6S"
$LOCATION"C1105"
PIN_NAMES_ROTATE"TRUE"
CDS_LMAN_SYM_OUTLINE"-25,50,25,-50"
CDS_LIB"pure_quanta"
CDS_LOCATION"C1105"
$SEC"1"
CDS_SEC"1";
"2"
$PN"2"27;
"1"
$PN"1"48;
%"Q_CAP_DIFFBUS"
"2","(3025,975)","0","pure_quanta","I61";
;
PART_NUMBER"SP_CH4221MEE01"
VALUE"DIFF BUS_0.22UF"
$LOCATION"C1104"
CDS_LIB"pure_quanta"
CDS_LMAN_SYM_OUTLINE"-25,50,25,-50"
TOLERANCE"20%"
PACK_TYPE"C0201"
MATERIAL"X6S"
VOLTAGE"6.3V"
PIN_NAMES_ROTATE"TRUE"
CDS_LOCATION"C1104"
$SEC"1"
CDS_SEC"1";
"2"
$PN"2"30;
"1"
$PN"1"45;
%"Q_CAP_DIFFBUS"
"2","(3025,1025)","0","pure_quanta","I62";
;
PART_NUMBER"SP_CH4221MEE01"
VALUE"DIFF BUS_0.22UF"
$LOCATION"C1103"
CDS_LIB"pure_quanta"
CDS_LMAN_SYM_OUTLINE"-25,50,25,-50"
TOLERANCE"20%"
PACK_TYPE"C0201"
MATERIAL"X6S"
VOLTAGE"6.3V"
PIN_NAMES_ROTATE"TRUE"
CDS_LOCATION"C1103"
$SEC"1"
CDS_SEC"1";
"2"
$PN"2"28;
"1"
$PN"1"36;
%"Q_CAP_DIFFBUS"
"2","(3025,1075)","0","pure_quanta","I63";
;
PART_NUMBER"SP_CH4221MEE01"
VALUE"DIFF BUS_0.22UF"
$LOCATION"C1102"
CDS_LIB"pure_quanta"
CDS_LMAN_SYM_OUTLINE"-25,50,25,-50"
TOLERANCE"20%"
PACK_TYPE"C0201"
MATERIAL"X6S"
VOLTAGE"6.3V"
PIN_NAMES_ROTATE"TRUE"
CDS_LOCATION"C1102"
$SEC"1"
CDS_SEC"1";
"2"
$PN"2"21;
"1"
$PN"1"37;
%"Q_CAP_DIFFBUS"
"2","(3025,1175)","0","pure_quanta","I64";
;
PART_NUMBER"SP_CH4221MEE01"
VALUE"DIFF BUS_0.22UF"
$LOCATION"C1100"
CDS_LIB"pure_quanta"
CDS_LMAN_SYM_OUTLINE"-25,50,25,-50"
TOLERANCE"20%"
PACK_TYPE"C0201"
MATERIAL"X6S"
VOLTAGE"6.3V"
PIN_NAMES_ROTATE"TRUE"
CDS_LOCATION"C1100"
$SEC"1"
CDS_SEC"1";
"2"
$PN"2"29;
"1"
$PN"1"39;
%"Q_CAP_DIFFBUS"
"2","(3025,1125)","0","pure_quanta","I65";
;
PART_NUMBER"SP_CH4221MEE01"
VALUE"DIFF BUS_0.22UF"
$LOCATION"C1101"
CDS_LIB"pure_quanta"
CDS_LMAN_SYM_OUTLINE"-25,50,25,-50"
TOLERANCE"20%"
PACK_TYPE"C0201"
MATERIAL"X6S"
VOLTAGE"6.3V"
PIN_NAMES_ROTATE"TRUE"
CDS_LOCATION"C1101"
$SEC"1"
CDS_SEC"1";
"2"
$PN"2"20;
"1"
$PN"1"38;
%"Q_CAP_DIFFBUS"
"2","(3025,1225)","0","pure_quanta","I66";
;
PART_NUMBER"SP_CH4221MEE01"
VALUE"DIFF BUS_0.22UF"
$LOCATION"C1099"
CDS_LIB"pure_quanta"
CDS_LMAN_SYM_OUTLINE"-25,50,25,-50"
TOLERANCE"20%"
PACK_TYPE"C0201"
MATERIAL"X6S"
VOLTAGE"6.3V"
PIN_NAMES_ROTATE"TRUE"
CDS_LOCATION"C1099"
$SEC"1"
CDS_SEC"1";
"2"
$PN"2"22;
"1"
$PN"1"44;
%"Q_CAP_DIFFBUS"
"2","(3025,1275)","0","pure_quanta","I67";
;
PART_NUMBER"SP_CH4221MEE01"
VALUE"DIFF BUS_0.22UF"
$LOCATION"C1098"
CDS_LIB"pure_quanta"
CDS_LMAN_SYM_OUTLINE"-25,50,25,-50"
TOLERANCE"20%"
PACK_TYPE"C0201"
MATERIAL"X6S"
VOLTAGE"6.3V"
PIN_NAMES_ROTATE"TRUE"
CDS_LOCATION"C1098"
$SEC"1"
CDS_SEC"1";
"2"
$PN"2"23;
"1"
$PN"1"40;
%"Q_CAP_DIFFBUS"
"2","(3025,1325)","0","pure_quanta","I68";
;
PART_NUMBER"SP_CH4221MEE01"
VALUE"DIFF BUS_0.22UF"
$LOCATION"C1996"
CDS_LIB"pure_quanta"
CDS_LMAN_SYM_OUTLINE"-25,50,25,-50"
PIN_NAMES_ROTATE"TRUE"
MATERIAL"X6S"
PACK_TYPE"C0201"
TOLERANCE"20%"
VOLTAGE"6.3V"
CDS_LOCATION"C1996"
$SEC"1"
CDS_SEC"1";
"2"
$PN"2"26;
"1"
$PN"1"43;
%"Q_CAP_DIFFBUS"
"2","(3025,1375)","0","pure_quanta","I69";
;
PART_NUMBER"SP_CH4221MEE01"
VALUE"DIFF BUS_0.22UF"
$LOCATION"C1995"
CDS_LIB"pure_quanta"
CDS_LMAN_SYM_OUTLINE"-25,50,25,-50"
TOLERANCE"20%"
PACK_TYPE"C0201"
MATERIAL"X6S"
VOLTAGE"6.3V"
PIN_NAMES_ROTATE"TRUE"
CDS_LOCATION"C1995"
$SEC"1"
CDS_SEC"1";
"2"
$PN"2"19;
"1"
$PN"1"42;
%"Q_CAP_DIFFBUS"
"2","(3025,1425)","0","pure_quanta","I70";
;
PART_NUMBER"SP_CH4221MEE01"
VALUE"DIFF BUS_0.22UF"
$LOCATION"C1994"
PIN_NAMES_ROTATE"TRUE"
VOLTAGE"6.3V"
MATERIAL"X6S"
PACK_TYPE"C0201"
TOLERANCE"20%"
CDS_LMAN_SYM_OUTLINE"-25,50,25,-50"
CDS_LIB"pure_quanta"
CDS_LOCATION"C1994"
$SEC"1"
CDS_SEC"1";
"2"
$PN"2"18;
"1"
$PN"1"47;
%"Q_CAP_DIFFBUS"
"2","(3025,1475)","0","pure_quanta","I71";
;
PART_NUMBER"SP_CH4221MEE01"
VALUE"DIFF BUS_0.22UF"
$LOCATION"C1993"
PIN_NAMES_ROTATE"TRUE"
VOLTAGE"6.3V"
MATERIAL"X6S"
PACK_TYPE"C0201"
TOLERANCE"20%"
CDS_LMAN_SYM_OUTLINE"-25,50,25,-50"
CDS_LIB"pure_quanta"
CDS_LOCATION"C1993"
$SEC"1"
CDS_SEC"1";
"2"
$PN"2"24;
"1"
$PN"1"46;
%"Q_CAP_DIFFBUS"
"2","(3025,1525)","0","pure_quanta","I72";
;
PART_NUMBER"SP_CH4221MEE01"
VALUE"DIFF BUS_0.22UF"
$LOCATION"C1992"
PIN_NAMES_ROTATE"TRUE"
VOLTAGE"6.3V"
MATERIAL"X6S"
PACK_TYPE"C0201"
TOLERANCE"20%"
CDS_LMAN_SYM_OUTLINE"-25,50,25,-50"
CDS_LIB"pure_quanta"
CDS_LOCATION"C1992"
$SEC"1"
CDS_SEC"1";
"2"
$PN"2"25;
"1"
$PN"1"41;
%"Q_CAP_DIFFBUS"
"2","(3025,1575)","0","pure_quanta","I73";
;
PART_NUMBER"SP_CH4221MEE01"
VALUE"DIFF BUS_0.22UF"
$LOCATION"C1991"
PIN_NAMES_ROTATE"TRUE"
VOLTAGE"6.3V"
MATERIAL"X6S"
PACK_TYPE"C0201"
TOLERANCE"20%"
CDS_LMAN_SYM_OUTLINE"-25,50,25,-50"
CDS_LIB"pure_quanta"
CDS_LOCATION"C1991"
$SEC"1"
CDS_SEC"1";
"2"
$PN"2"17;
"1"
$PN"1"34;
%"Q_CAP_DIFFBUS"
"2","(3025,1625)","0","pure_quanta","I74";
;
PART_NUMBER"SP_CH4221MEE01"
VALUE"DIFF BUS_0.22UF"
$LOCATION"C1990"
PIN_NAMES_ROTATE"TRUE"
VOLTAGE"6.3V"
MATERIAL"X6S"
PACK_TYPE"C0201"
TOLERANCE"20%"
CDS_LMAN_SYM_OUTLINE"-25,50,25,-50"
CDS_LIB"pure_quanta"
CDS_LOCATION"C1990"
$SEC"1"
CDS_SEC"1";
"2"
$PN"2"15;
"1"
$PN"1"35;
%"Q_CAP_DIFFBUS"
"2","(3025,1675)","0","pure_quanta","I75";
;
PART_NUMBER"SP_CH4221MEE01"
VALUE"DIFF BUS_0.22UF"
$LOCATION"C1989"
TOLERANCE"20%"
PACK_TYPE"C0201"
MATERIAL"X6S"
VOLTAGE"6.3V"
PIN_NAMES_ROTATE"TRUE"
CDS_LIB"pure_quanta"
CDS_LMAN_SYM_OUTLINE"-25,50,25,-50"
CDS_LOCATION"C1989"
$SEC"1"
CDS_SEC"1";
"2"
$PN"2"16;
"1"
$PN"1"33;
%"Q_CAP_DIFFBUS"
"2","(3025,1725)","0","pure_quanta","I76";
;
PART_NUMBER"SP_CH4221MEE01"
VALUE"DIFF BUS_0.22UF"
$LOCATION"C2078"
CDS_LIB"pure_quanta"
CDS_LMAN_SYM_OUTLINE"-25,50,25,-50"
PIN_NAMES_ROTATE"TRUE"
VOLTAGE"6.3V"
MATERIAL"X6S"
PACK_TYPE"C0201"
TOLERANCE"20%"
CDS_LOCATION"C2078"
$SEC"1"
CDS_SEC"1";
"2"
$PN"2"13;
"1"
$PN"1"32;
%"Q_CAP_DIFFBUS"
"2","(3025,1775)","0","pure_quanta","I77";
;
PART_NUMBER"SP_CH4221MEE01"
VALUE"DIFF BUS_0.22UF"
$LOCATION"C2077"
CDS_LIB"pure_quanta"
CDS_LMAN_SYM_OUTLINE"-25,50,25,-50"
TOLERANCE"20%"
PACK_TYPE"C0201"
MATERIAL"X6S"
VOLTAGE"6.3V"
PIN_NAMES_ROTATE"TRUE"
CDS_LOCATION"C2077"
$SEC"1"
CDS_SEC"1";
"2"
$PN"2"12;
"1"
$PN"1"31;
%"Q_CAP"
"2","(3025,1825)","0","pure_quanta","I78";
;
PART_NUMBER"CH4101KEE01"
PACK_TYPE"C0201"
MATERIAL"X6S"
VALUE"0.1UF"
LOCATION"C1097"
CDS_LIB"pure_quanta"
VOLTAGE"6.3V"
TOLERANCE"10%"
$SEC"1"
CDS_SEC"1";
"A"
$PN"1"58;
"B"
$PN"2"10;
%"Q_CAP_DIFFBUS"
"2","(3025,1925)","0","pure_quanta","I79";
;
PART_NUMBER"SP_CH4221MEE01"
VALUE"DIFF BUS_0.22UF"
$LOCATION"C2076"
CDS_LIB"pure_quanta"
CDS_LMAN_SYM_OUTLINE"-25,50,25,-50"
TOLERANCE"20%"
PACK_TYPE"C0201"
MATERIAL"X6S"
VOLTAGE"6.3V"
PIN_NAMES_ROTATE"TRUE"
CDS_LOCATION"C2076"
$SEC"1"
CDS_SEC"1";
"2"
$PN"2"11;
"1"
$PN"1"57;
%"Q_CAP"
"2","(3025,1875)","0","pure_quanta","I80";
;
PART_NUMBER"CH4101KEE01"
PACK_TYPE"C0201"
VALUE"0.1UF"
MATERIAL"X6S"
$LOCATION"C1096"
CDS_LIB"pure_quanta"
VOLTAGE"6.3V"
TOLERANCE"10%"
CDS_LOCATION"C1096"
$SEC"1"
CDS_SEC"1";
"A"
$PN"1"59;
"B"
$PN"2"9;
%"Q_CAP_DIFFBUS"
"2","(3025,1975)","0","pure_quanta","I81";
;
PART_NUMBER"SP_CH4221MEE01"
VALUE"DIFF BUS_0.22UF"
$LOCATION"C2075"
CDS_LIB"pure_quanta"
CDS_LMAN_SYM_OUTLINE"-25,50,25,-50"
TOLERANCE"20%"
PACK_TYPE"C0201"
MATERIAL"X6S"
VOLTAGE"6.3V"
PIN_NAMES_ROTATE"TRUE"
CDS_LOCATION"C2075"
$SEC"1"
CDS_SEC"1";
"2"
$PN"2"8;
"1"
$PN"1"56;
%"Q_CAP_DIFFBUS"
"2","(3025,2025)","0","pure_quanta","I82";
;
PART_NUMBER"SP_CH4221MEE01"
VALUE"DIFF BUS_0.22UF"
$LOCATION"C2074"
CDS_LIB"pure_quanta"
CDS_LMAN_SYM_OUTLINE"-25,50,25,-50"
TOLERANCE"20%"
PACK_TYPE"C0201"
MATERIAL"X6S"
VOLTAGE"6.3V"
PIN_NAMES_ROTATE"TRUE"
CDS_LOCATION"C2074"
$SEC"1"
CDS_SEC"1";
"2"
$PN"2"14;
"1"
$PN"1"60;
%"Q_CAP_DIFFBUS"
"2","(3025,2075)","0","pure_quanta","I83";
;
PART_NUMBER"SP_CH4221MEE01"
VALUE"DIFF BUS_0.22UF"
$LOCATION"C2073"
CDS_LIB"pure_quanta"
CDS_LMAN_SYM_OUTLINE"-25,50,25,-50"
TOLERANCE"20%"
PACK_TYPE"C0201"
MATERIAL"X6S"
VOLTAGE"6.3V"
PIN_NAMES_ROTATE"TRUE"
CDS_LOCATION"C2073"
$SEC"1"
CDS_SEC"1";
"2"
$PN"2"7;
"1"
$PN"1"55;
END.
